# T6G (Grand Teton) — schematic netlist excerpt (pin names and nets, part order shuffled) for the footprints in the layout excerpt that follows; sources: Cadence DE-HDL packaged netlist, KiCad conversion of 04192023_DAF0TMB3IC0_F0TG_MB_C_brd_V02_OCP.brd

PR409  Q_RES  0 5% CHIP  pkg 0402LF  page 224 : A = NC_PVDD11_S3_P1_IMON8 ; B = GND
PC140_6  Q_CAP  1UF 25V 10% X6S  pkg C0402  page 220 : A = SW_P12V_AUX_PVDDCR_CPU1_P1_FLT ; B = GND

(kicad_pcb
	(version 20260206)
	(generator "pcbnew")
	(generator_version "10.0")
	(general
		(thickness 1.6)
		(legacy_teardrops no)
	)
	(paper "A4")
	(title_block
		(title "04192023_DAF0TMB3IC0_F0TG_MB_C_brd_V02_OCP.brd")
		(comment 1 "Grand Teton / footprints 3196-3197 of 8354")
	)
	(layers
		(0 "F.Cu" signal "TOP")
		(4 "In1.Cu" signal "GND")
		(6 "In2.Cu" signal "IN1")
		(8 "In3.Cu" signal "GND1")
		(10 "In4.Cu" signal "IN2")
		(12 "In5.Cu" signal "GND2")
		(14 "In6.Cu" signal "IN3")
		(16 "In7.Cu" signal "GND3")
		(18 "In8.Cu" signal "VCC")
		(20 "In9.Cu" signal "VCC1")
		(22 "In10.Cu" signal "GND4")
		(24 "In11.Cu" signal "IN4")
		(26 "In12.Cu" signal "GND5")
		(28 "In13.Cu" signal "IN5")
		(30 "In14.Cu" signal "GND6")
		(32 "In15.Cu" signal "IN6")
		(34 "In16.Cu" signal "GND7")
		(2 "B.Cu" signal "BOTTOM")
		(9 "F.Adhes" user "F.Adhesive")
		(11 "B.Adhes" user "B.Adhesive")
		(13 "F.Paste" user "Package Geometry/Pastemask Top")
		(15 "B.Paste" user "Package Geometry/Pastemask Bottom")
		(5 "F.SilkS" user "Ref Des/Silkscreen Top")
		(7 "B.SilkS" user "Ref Des/Silkscreen Bottom")
		(1 "F.Mask" user "Board Geometry/Soldermask Top")
		(3 "B.Mask" user "Board Geometry/Soldermask Bottom")
		(17 "Dwgs.User" user "User.Drawings")
		(19 "Cmts.User" user "User.Comments")
		(21 "Eco1.User" user "User.Eco1")
		(23 "Eco2.User" user "User.Eco2")
		(25 "Edge.Cuts" user "Board Geometry/Outline")
		(27 "Margin" user)
		(31 "F.CrtYd" user "Package Geometry/Place Bound Top")
		(29 "B.CrtYd" user "Package Geometry/Place Bound Bottom")
		(35 "F.Fab" user "Ref Des/Assembly Top")
		(33 "B.Fab" user "Ref Des/Assembly Bottom")
	)
	(footprint ""
		(layer "F.Cu")
		(at 167.090344 -344.153998 -90)
		(property "Reference" "PR409"
			(at 0 0 270)
			(layer "F.SilkS")
			(hide yes)
			(effects
				(font
					(size 1.27 1.27)
				)
			)
		)
		(property "Value" ""
			(at 0 0 270)
			(layer "F.Fab")
			(effects
				(font
					(size 1.27 1.27)
				)
			)
		)
		(duplicate_pad_numbers_are_jumpers no)
		(fp_line
			(start -0.7874 0.4064)
			(end -0.7874 -0.4064)
			(stroke
				(width 0.1524)
				(type default)
			)
			(layer "F.SilkS")
		)
		(fp_line
			(start 0.7874 0.4064)
			(end -0.7874 0.4064)
			(stroke
				(width 0.1524)
				(type default)
			)
			(layer "F.SilkS")
		)
		(fp_line
			(start -0.7874 -0.4064)
			(end 0.7874 -0.4064)
			(stroke
				(width 0.1524)
				(type default)
			)
			(layer "F.SilkS")
		)
		(fp_line
			(start 0.7874 -0.4064)
			(end 0.7874 0.4064)
			(stroke
				(width 0.1524)
				(type default)
			)
			(layer "F.SilkS")
		)
		(fp_line
			(start -0.67945 0.3048)
			(end -0.67945 -0.305054)
			(stroke
				(width 0.1)
				(type default)
			)
			(layer "F.Fab")
		)
		(fp_line
			(start -0.12065 0.3048)
			(end -0.67945 0.3048)
			(stroke
				(width 0.1)
				(type default)
			)
			(layer "F.Fab")
		)
		(fp_line
			(start 0.120396 0.3048)
			(end 0.120396 0.2794)
			(stroke
				(width 0.1)
				(type default)
			)
			(layer "F.Fab")
		)
		(fp_line
			(start 0.67945 0.3048)
			(end 0.120396 0.3048)
			(stroke
				(width 0.1)
				(type default)
			)
			(layer "F.Fab")
		)
		(fp_line
			(start -0.12065 0.2794)
			(end -0.12065 0.3048)
			(stroke
				(width 0.1)
				(type default)
			)
			(layer "F.Fab")
		)
		(fp_line
			(start 0.120396 0.2794)
			(end -0.12065 0.2794)
			(stroke
				(width 0.1)
				(type default)
			)
			(layer "F.Fab")
		)
		(fp_line
			(start -0.12065 -0.2794)
			(end 0.12065 -0.2794)
			(stroke
				(width 0.1)
				(type default)
			)
			(layer "F.Fab")
		)
		(fp_line
			(start 0.12065 -0.2794)
			(end 0.12065 -0.3048)
			(stroke
				(width 0.1)
				(type default)
			)
			(layer "F.Fab")
		)
		(fp_line
			(start 0.12065 -0.3048)
			(end 0.67945 -0.3048)
			(stroke
				(width 0.1)
				(type default)
			)
			(layer "F.Fab")
		)
		(fp_line
			(start 0.67945 -0.3048)
			(end 0.67945 0.3048)
			(stroke
				(width 0.1)
				(type default)
			)
			(layer "F.Fab")
		)
		(fp_line
			(start -0.67945 -0.305054)
			(end -0.12065 -0.305054)
			(stroke
				(width 0.1)
				(type default)
			)
			(layer "F.Fab")
		)
		(fp_line
			(start -0.12065 -0.305054)
			(end -0.12065 -0.2794)
			(stroke
				(width 0.1)
				(type default)
			)
			(layer "F.Fab")
		)
		(pad "1" smd circle
			(at -0.40005 0 270)
			(size 0 0)
			(layers "F.Cu" "F.Mask" "F.Paste")
			(net "NC_PVDD11_S3_P1_IMON8")
		)
		(pad "2" smd circle
			(at 0.40005 0 270)
			(size 0 0)
			(layers "F.Cu" "F.Mask" "F.Paste")
			(net "GND")
		)
	)
	(footprint ""
		(layer "F.Cu")
		(at 107.363768 -340.08949 -90)
		(property "Reference" "PC140_6"
			(at 0 0 270)
			(layer "F.SilkS")
			(hide yes)
			(effects
				(font
					(size 1.27 1.27)
				)
			)
		)
		(property "Value" ""
			(at 0 0 270)
			(layer "F.Fab")
			(effects
				(font
					(size 1.27 1.27)
				)
			)
		)
		(duplicate_pad_numbers_are_jumpers no)
		(fp_line
			(start -0.7874 0.4064)
			(end -0.7874 -0.4064)
			(stroke
				(width 0.1524)
				(type default)
			)
			(layer "F.SilkS")
		)
		(fp_line
			(start 0.7874 0.4064)
			(end -0.7874 0.4064)
			(stroke
				(width 0.1524)
				(type default)
			)
			(layer "F.SilkS")
		)
		(fp_line
			(start -0.7874 -0.4064)
			(end 0.7874 -0.4064)
			(stroke
				(width 0.1524)
				(type default)
			)
			(layer "F.SilkS")
		)
		(fp_line
			(start 0.7874 -0.4064)
			(end 0.7874 0.4064)
			(stroke
				(width 0.1524)
				(type default)
			)
			(layer "F.SilkS")
		)
		(fp_line
			(start -0.67945 0.3048)
			(end -0.67945 -0.305054)
			(stroke
				(width 0.1)
				(type default)
			)
			(layer "F.Fab")
		)
		(fp_line
			(start -0.12065 0.3048)
			(end -0.67945 0.3048)
			(stroke
				(width 0.1)
				(type default)
			)
			(layer "F.Fab")
		)
		(fp_line
			(start 0.120396 0.3048)
			(end 0.120396 0.2794)
			(stroke
				(width 0.1)
				(type default)
			)
			(layer "F.Fab")
		)
		(fp_line
			(start 0.67945 0.3048)
			(end 0.120396 0.3048)
			(stroke
				(width 0.1)
				(type default)
			)
			(layer "F.Fab")
		)
		(fp_line
			(start -0.12065 0.2794)
			(end -0.12065 0.3048)
			(stroke
				(width 0.1)
				(type default)
			)
			(layer "F.Fab")
		)
		(fp_line
			(start 0.120396 0.2794)
			(end -0.12065 0.2794)
			(stroke
				(width 0.1)
				(type default)
			)
			(layer "F.Fab")
		)
		(fp_line
			(start -0.12065 -0.2794)
			(end 0.12065 -0.2794)
			(stroke
				(width 0.1)
				(type default)
			)
			(layer "F.Fab")
		)
		(fp_line
			(start 0.12065 -0.2794)
			(end 0.12065 -0.3048)
			(stroke
				(width 0.1)
				(type default)
			)
			(layer "F.Fab")
		)
		(fp_line
			(start 0.12065 -0.3048)
			(end 0.67945 -0.3048)
			(stroke
				(width 0.1)
				(type default)
			)
			(layer "F.Fab")
		)
		(fp_line
			(start 0.67945 -0.3048)
			(end 0.67945 0.3048)
			(stroke
				(width 0.1)
				(type default)
			)
			(layer "F.Fab")
		)
		(fp_line
			(start -0.67945 -0.305054)
			(end -0.12065 -0.305054)
			(stroke
				(width 0.1)
				(type default)
			)
			(layer "F.Fab")
		)
		(fp_line
			(start -0.12065 -0.305054)
			(end -0.12065 -0.2794)
			(stroke
				(width 0.1)
				(type default)
			)
			(layer "F.Fab")
		)
		(pad "1" smd circle
			(at -0.40005 0 270)
			(size 0 0)
			(layers "F.Cu" "F.Mask" "F.Paste")
			(net "SW_P12V_AUX_PVDDCR_CPU1_P1_FLT")
		)
		(pad "2" smd circle
			(at 0.40005 0 270)
			(size 0 0)
			(layers "F.Cu" "F.Mask" "F.Paste")
			(net "GND")
		)
	)
)
